# T6G (Grand Teton) — schematic netlist excerpt (pin names and nets, part order shuffled) for the footprints in the layout excerpt that follows; sources: Cadence DE-HDL packaged netlist, KiCad conversion of 04192023_DAF0TMB3IC0_F0TG_MB_C_brd_V02_OCP.brd

R6009  Q_RES  0 5% CHIP  pkg 0402LF  page 150 : A = SGPIO_SCM_CLK_<0> ; B = SGPIO_SCM_CLK_R_<0>
R735  Q_RES  1K 1% CHIP  pkg 0201LF  page 331 : A = P1V8_CPU1_RT_1D ; B = RT_CPU1_P1_ADDR3

(kicad_pcb
	(version 20260206)
	(generator "pcbnew")
	(generator_version "10.0")
	(general
		(thickness 1.6)
		(legacy_teardrops no)
	)
	(paper "A4")
	(title_block
		(title "04192023_DAF0TMB3IC0_F0TG_MB_C_brd_V02_OCP.brd")
		(comment 1 "Grand Teton / footprints 4567-4569 of 8354")
	)
	(layers
		(0 "F.Cu" signal "TOP")
		(4 "In1.Cu" signal "GND")
		(6 "In2.Cu" signal "IN1")
		(8 "In3.Cu" signal "GND1")
		(10 "In4.Cu" signal "IN2")
		(12 "In5.Cu" signal "GND2")
		(14 "In6.Cu" signal "IN3")
		(16 "In7.Cu" signal "GND3")
		(18 "In8.Cu" signal "VCC")
		(20 "In9.Cu" signal "VCC1")
		(22 "In10.Cu" signal "GND4")
		(24 "In11.Cu" signal "IN4")
		(26 "In12.Cu" signal "GND5")
		(28 "In13.Cu" signal "IN5")
		(30 "In14.Cu" signal "GND6")
		(32 "In15.Cu" signal "IN6")
		(34 "In16.Cu" signal "GND7")
		(2 "B.Cu" signal "BOTTOM")
		(9 "F.Adhes" user "F.Adhesive")
		(11 "B.Adhes" user "B.Adhesive")
		(13 "F.Paste" user "Package Geometry/Pastemask Top")
		(15 "B.Paste" user "Package Geometry/Pastemask Bottom")
		(5 "F.SilkS" user "Ref Des/Silkscreen Top")
		(7 "B.SilkS" user "Ref Des/Silkscreen Bottom")
		(1 "F.Mask" user "Board Geometry/Soldermask Top")
		(3 "B.Mask" user "Board Geometry/Soldermask Bottom")
		(17 "Dwgs.User" user "User.Drawings")
		(19 "Cmts.User" user "User.Comments")
		(21 "Eco1.User" user "User.Eco1")
		(23 "Eco2.User" user "User.Eco2")
		(25 "Edge.Cuts" user "Board Geometry/Outline")
		(27 "Margin" user)
		(31 "F.CrtYd" user "Package Geometry/Place Bound Top")
		(29 "B.CrtYd" user "Package Geometry/Place Bound Bottom")
		(35 "F.Fab" user "Ref Des/Assembly Top")
		(33 "B.Fab" user "Ref Des/Assembly Bottom")
	)
	(footprint ""
		(layer "F.Cu")
		(at 173.9392 -94.833948 -90)
		(property "Reference" "R6009"
			(at 0 0 270)
			(layer "F.SilkS")
			(hide yes)
			(effects
				(font
					(size 1.27 1.27)
				)
			)
		)
		(property "Value" ""
			(at 0 0 270)
			(layer "F.Fab")
			(effects
				(font
					(size 1.27 1.27)
				)
			)
		)
		(duplicate_pad_numbers_are_jumpers no)
		(fp_line
			(start -0.7874 0.4064)
			(end -0.7874 -0.4064)
			(stroke
				(width 0.1524)
				(type default)
			)
			(layer "F.SilkS")
		)
		(fp_line
			(start 0.7874 0.4064)
			(end -0.7874 0.4064)
			(stroke
				(width 0.1524)
				(type default)
			)
			(layer "F.SilkS")
		)
		(fp_line
			(start -0.7874 -0.4064)
			(end 0.7874 -0.4064)
			(stroke
				(width 0.1524)
				(type default)
			)
			(layer "F.SilkS")
		)
		(fp_line
			(start 0.7874 -0.4064)
			(end 0.7874 0.4064)
			(stroke
				(width 0.1524)
				(type default)
			)
			(layer "F.SilkS")
		)
		(fp_line
			(start -0.67945 0.3048)
			(end -0.67945 -0.305054)
			(stroke
				(width 0.1)
				(type default)
			)
			(layer "F.Fab")
		)
		(fp_line
			(start -0.12065 0.3048)
			(end -0.67945 0.3048)
			(stroke
				(width 0.1)
				(type default)
			)
			(layer "F.Fab")
		)
		(fp_line
			(start 0.120396 0.3048)
			(end 0.120396 0.2794)
			(stroke
				(width 0.1)
				(type default)
			)
			(layer "F.Fab")
		)
		(fp_line
			(start 0.67945 0.3048)
			(end 0.120396 0.3048)
			(stroke
				(width 0.1)
				(type default)
			)
			(layer "F.Fab")
		)
		(fp_line
			(start -0.12065 0.2794)
			(end -0.12065 0.3048)
			(stroke
				(width 0.1)
				(type default)
			)
			(layer "F.Fab")
		)
		(fp_line
			(start 0.120396 0.2794)
			(end -0.12065 0.2794)
			(stroke
				(width 0.1)
				(type default)
			)
			(layer "F.Fab")
		)
		(fp_line
			(start -0.12065 -0.2794)
			(end 0.12065 -0.2794)
			(stroke
				(width 0.1)
				(type default)
			)
			(layer "F.Fab")
		)
		(fp_line
			(start 0.12065 -0.2794)
			(end 0.12065 -0.3048)
			(stroke
				(width 0.1)
				(type default)
			)
			(layer "F.Fab")
		)
		(fp_line
			(start 0.12065 -0.3048)
			(end 0.67945 -0.3048)
			(stroke
				(width 0.1)
				(type default)
			)
			(layer "F.Fab")
		)
		(fp_line
			(start 0.67945 -0.3048)
			(end 0.67945 0.3048)
			(stroke
				(width 0.1)
				(type default)
			)
			(layer "F.Fab")
		)
		(fp_line
			(start -0.67945 -0.305054)
			(end -0.12065 -0.305054)
			(stroke
				(width 0.1)
				(type default)
			)
			(layer "F.Fab")
		)
		(fp_line
			(start -0.12065 -0.305054)
			(end -0.12065 -0.2794)
			(stroke
				(width 0.1)
				(type default)
			)
			(layer "F.Fab")
		)
		(pad "1" smd circle
			(at -0.40005 0 270)
			(size 0 0)
			(layers "F.Cu" "F.Mask" "F.Paste")
			(net "SGPIO_SCM_CLK_<0>")
		)
		(pad "2" smd circle
			(at 0.40005 0 270)
			(size 0 0)
			(layers "F.Cu" "F.Mask" "F.Paste")
			(net "SGPIO_SCM_CLK_R_<0>")
		)
	)
	(footprint ""
		(layer "F.Cu")
		(at 104.409748 -385.5212 90)
		(property "Reference" "R735"
			(at 0 0 90)
			(layer "F.SilkS")
			(hide yes)
			(effects
				(font
					(size 1.27 1.27)
				)
			)
		)
		(property "Value" ""
			(at 0 0 90)
			(layer "F.Fab")
			(effects
				(font
					(size 1.27 1.27)
				)
			)
		)
		(duplicate_pad_numbers_are_jumpers no)
		(fp_line
			(start 0.32512 -0.175006)
			(end 0.32512 0.175006)
			(stroke
				(width 0.1)
				(type default)
			)
			(layer "F.Fab")
		)
		(fp_line
			(start -0.32512 -0.175006)
			(end 0.32512 -0.175006)
			(stroke
				(width 0.1)
				(type default)
			)
			(layer "F.Fab")
		)
		(fp_line
			(start 0.32512 0.175006)
			(end -0.32512 0.175006)
			(stroke
				(width 0.1)
				(type default)
			)
			(layer "F.Fab")
		)
		(fp_line
			(start -0.32512 0.175006)
			(end -0.32512 -0.175006)
			(stroke
				(width 0.1)
				(type default)
			)
			(layer "F.Fab")
		)
		(pad "1" smd rect
			(at -0.2667 0 90)
			(size 0.3048 0.381)
			(layers "F.Cu" "F.Mask" "F.Paste")
			(net "P1V8_CPU1_RT_1D")
		)
		(pad "2" smd rect
			(at 0.2667 0 270)
			(size 0.3048 0.381)
			(layers "F.Cu" "F.Mask" "F.Paste")
			(net "RT_CPU1_P1_ADDR3")
		)
	)
	(footprint ""
		(layer "F.Cu")
		(at 291.652706 -140.770864 180)
		(property "Reference" ""
			(at 0 0 180)
			(layer "F.SilkS")
			(hide yes)
			(effects
				(font
					(size 1.27 1.27)
				)
			)
		)
		(property "Value" ""
			(at 0 0 180)
			(layer "F.Fab")
			(effects
				(font
					(size 1.27 1.27)
				)
			)
		)
		(duplicate_pad_numbers_are_jumpers no)
		(pad "1" smd circle
			(at 0 0 180)
			(size 0.9906 0.9906)
			(layers "F.Cu" "F.Mask" "F.Paste")
			(net "Net_2237")
		)
		(zone
			(layer "F.Cu")
			(hatch none 0.5)
			(connect_pads
				(clearance 0)
			)
			(min_thickness 0.25)
			(keepout
				(tracks not_allowed)
				(vias allowed)
				(pads allowed)
				(copperpour not_allowed)
				(footprints allowed)
			)
			(placement
				(enabled no)
				(sheetname "")
			)
			(fill
				(thermal_gap 0.5)
				(thermal_bridge_width 0.5)
				(island_removal_mode 0)
			)
			(polygon
				(pts
					(arc
						(start 293.278306 -140.770864)
						(mid 290.027106 -140.770864)
						(end 293.278306 -140.770864)
					)
				)
			)
		)
	)
)
